(kicad_pcb
	(version 20260206)
	(generator "pcbnew")
	(generator_version "10.0")
	(general
		(thickness 1.6)
		(legacy_teardrops no)
	)
	(paper "A4")
	(title_block
		(title "04192023_DAF0TMB3IC0_F0TG_MB_C_brd_V02_OCP.brd")
		(comment 1 "Grand Teton / footprints 7244-7250 of 8354")
	)
	(layers
		(0 "F.Cu" signal "TOP")
		(4 "In1.Cu" signal "GND")
		(6 "In2.Cu" signal "IN1")
		(8 "In3.Cu" signal "GND1")
		(10 "In4.Cu" signal "IN2")
		(12 "In5.Cu" signal "GND2")
		(14 "In6.Cu" signal "IN3")
		(16 "In7.Cu" signal "GND3")
		(18 "In8.Cu" signal "VCC")
		(20 "In9.Cu" signal "VCC1")
		(22 "In10.Cu" signal "GND4")
		(24 "In11.Cu" signal "IN4")
		(26 "In12.Cu" signal "GND5")
		(28 "In13.Cu" signal "IN5")
		(30 "In14.Cu" signal "GND6")
		(32 "In15.Cu" signal "IN6")
		(34 "In16.Cu" signal "GND7")
		(2 "B.Cu" signal "BOTTOM")
		(9 "F.Adhes" user "F.Adhesive")
		(11 "B.Adhes" user "B.Adhesive")
		(13 "F.Paste" user "Package Geometry/Pastemask Top")
		(15 "B.Paste" user "Package Geometry/Pastemask Bottom")
		(5 "F.SilkS" user "Ref Des/Silkscreen Top")
		(7 "B.SilkS" user "Ref Des/Silkscreen Bottom")
		(1 "F.Mask" user "Board Geometry/Soldermask Top")
		(3 "B.Mask" user "Board Geometry/Soldermask Bottom")
		(17 "Dwgs.User" user "User.Drawings")
		(19 "Cmts.User" user "User.Comments")
		(21 "Eco1.User" user "User.Eco1")
		(23 "Eco2.User" user "User.Eco2")
		(25 "Edge.Cuts" user "Board Geometry/Outline")
		(27 "Margin" user)
		(31 "F.CrtYd" user "Package Geometry/Place Bound Top")
		(29 "B.CrtYd" user "Package Geometry/Place Bound Bottom")
		(35 "F.Fab" user "Ref Des/Assembly Top")
		(33 "B.Fab" user "Ref Des/Assembly Bottom")
	)
	(footprint ""
		(layer "B.Cu")
		(at 136.040114 -35.866578)
		(property "Reference" "C6037"
			(at 0 0 0)
			(layer "B.SilkS")
			(hide yes)
			(effects
				(font
					(size 1.27 1.27)
				)
				(justify mirror)
			)
		)
		(property "Value" ""
			(at 0 0 0)
			(layer "B.Fab")
			(effects
				(font
					(size 1.27 1.27)
				)
				(justify mirror)
			)
		)
		(duplicate_pad_numbers_are_jumpers no)
		(fp_line
			(start -0.7874 -0.4064)
			(end -0.7874 0.4064)
			(stroke
				(width 0.1524)
				(type default)
			)
			(layer "B.SilkS")
		)
		(fp_line
			(start -0.7874 0.4064)
			(end 0.7874 0.4064)
			(stroke
				(width 0.1524)
				(type default)
			)
			(layer "B.SilkS")
		)
		(fp_line
			(start 0.7874 -0.4064)
			(end -0.7874 -0.4064)
			(stroke
				(width 0.1524)
				(type default)
			)
			(layer "B.SilkS")
		)
		(fp_line
			(start 0.7874 0.4064)
			(end 0.7874 -0.4064)
			(stroke
				(width 0.1524)
				(type default)
			)
			(layer "B.SilkS")
		)
		(fp_line
			(start -0.67945 -0.3048)
			(end -0.67945 0.3048)
			(stroke
				(width 0.1)
				(type default)
			)
			(layer "B.Fab")
		)
		(fp_line
			(start -0.67945 0.3048)
			(end -0.120396 0.3048)
			(stroke
				(width 0.1)
				(type default)
			)
			(layer "B.Fab")
		)
		(fp_line
			(start -0.12065 -0.3048)
			(end -0.67945 -0.3048)
			(stroke
				(width 0.1)
				(type default)
			)
			(layer "B.Fab")
		)
		(fp_line
			(start -0.12065 -0.2794)
			(end -0.12065 -0.3048)
			(stroke
				(width 0.1)
				(type default)
			)
			(layer "B.Fab")
		)
		(fp_line
			(start -0.120396 0.2794)
			(end 0.12065 0.2794)
			(stroke
				(width 0.1)
				(type default)
			)
			(layer "B.Fab")
		)
		(fp_line
			(start -0.120396 0.3048)
			(end -0.120396 0.2794)
			(stroke
				(width 0.1)
				(type default)
			)
			(layer "B.Fab")
		)
		(fp_line
			(start 0.12065 -0.305054)
			(end 0.12065 -0.2794)
			(stroke
				(width 0.1)
				(type default)
			)
			(layer "B.Fab")
		)
		(fp_line
			(start 0.12065 -0.2794)
			(end -0.12065 -0.2794)
			(stroke
				(width 0.1)
				(type default)
			)
			(layer "B.Fab")
		)
		(fp_line
			(start 0.12065 0.2794)
			(end 0.12065 0.3048)
			(stroke
				(width 0.1)
				(type default)
			)
			(layer "B.Fab")
		)
		(fp_line
			(start 0.12065 0.3048)
			(end 0.67945 0.3048)
			(stroke
				(width 0.1)
				(type default)
			)
			(layer "B.Fab")
		)
		(fp_line
			(start 0.67945 -0.305054)
			(end 0.12065 -0.305054)
			(stroke
				(width 0.1)
				(type default)
			)
			(layer "B.Fab")
		)
		(fp_line
			(start 0.67945 0.3048)
			(end 0.67945 -0.305054)
			(stroke
				(width 0.1)
				(type default)
			)
			(layer "B.Fab")
		)
		(pad "1" smd circle
			(at 0.40005 0 180)
			(size 0 0)
			(layers "B.Cu" "B.Mask" "B.Paste")
			(net "P1V2_CPU0_USB_DVDD12")
		)
		(pad "2" smd circle
			(at -0.40005 0 180)
			(size 0 0)
			(layers "B.Cu" "B.Mask" "B.Paste")
			(net "GND")
		)
	)
	(footprint ""
		(layer "B.Cu")
		(at 367.614454 -267.498576)
		(property "Reference" "C2211"
			(at 0 0 0)
			(layer "B.SilkS")
			(hide yes)
			(effects
				(font
					(size 1.27 1.27)
				)
				(justify mirror)
			)
		)
		(property "Value" ""
			(at 0 0 0)
			(layer "B.Fab")
			(effects
				(font
					(size 1.27 1.27)
				)
				(justify mirror)
			)
		)
		(duplicate_pad_numbers_are_jumpers no)
		(fp_line
			(start -0.7874 -0.4064)
			(end -0.7874 0.4064)
			(stroke
				(width 0.1524)
				(type default)
			)
			(layer "B.SilkS")
		)
		(fp_line
			(start -0.7874 0.4064)
			(end 0.7874 0.4064)
			(stroke
				(width 0.1524)
				(type default)
			)
			(layer "B.SilkS")
		)
		(fp_line
			(start 0.7874 -0.4064)
			(end -0.7874 -0.4064)
			(stroke
				(width 0.1524)
				(type default)
			)
			(layer "B.SilkS")
		)
		(fp_line
			(start 0.7874 0.4064)
			(end 0.7874 -0.4064)
			(stroke
				(width 0.1524)
				(type default)
			)
			(layer "B.SilkS")
		)
		(fp_line
			(start -0.67945 -0.3048)
			(end -0.67945 0.3048)
			(stroke
				(width 0.1)
				(type default)
			)
			(layer "B.Fab")
		)
		(fp_line
			(start -0.67945 0.3048)
			(end -0.120396 0.3048)
			(stroke
				(width 0.1)
				(type default)
			)
			(layer "B.Fab")
		)
		(fp_line
			(start -0.12065 -0.3048)
			(end -0.67945 -0.3048)
			(stroke
				(width 0.1)
				(type default)
			)
			(layer "B.Fab")
		)
		(fp_line
			(start -0.12065 -0.2794)
			(end -0.12065 -0.3048)
			(stroke
				(width 0.1)
				(type default)
			)
			(layer "B.Fab")
		)
		(fp_line
			(start -0.120396 0.2794)
			(end 0.12065 0.2794)
			(stroke
				(width 0.1)
				(type default)
			)
			(layer "B.Fab")
		)
		(fp_line
			(start -0.120396 0.3048)
			(end -0.120396 0.2794)
			(stroke
				(width 0.1)
				(type default)
			)
			(layer "B.Fab")
		)
		(fp_line
			(start 0.12065 -0.305054)
			(end 0.12065 -0.2794)
			(stroke
				(width 0.1)
				(type default)
			)
			(layer "B.Fab")
		)
		(fp_line
			(start 0.12065 -0.2794)
			(end -0.12065 -0.2794)
			(stroke
				(width 0.1)
				(type default)
			)
			(layer "B.Fab")
		)
		(fp_line
			(start 0.12065 0.2794)
			(end 0.12065 0.3048)
			(stroke
				(width 0.1)
				(type default)
			)
			(layer "B.Fab")
		)
		(fp_line
			(start 0.12065 0.3048)
			(end 0.67945 0.3048)
			(stroke
				(width 0.1)
				(type default)
			)
			(layer "B.Fab")
		)
		(fp_line
			(start 0.67945 -0.305054)
			(end 0.12065 -0.305054)
			(stroke
				(width 0.1)
				(type default)
			)
			(layer "B.Fab")
		)
		(fp_line
			(start 0.67945 0.3048)
			(end 0.67945 -0.305054)
			(stroke
				(width 0.1)
				(type default)
			)
			(layer "B.Fab")
		)
		(pad "1" smd circle
			(at 0.40005 0 180)
			(size 0 0)
			(layers "B.Cu" "B.Mask" "B.Paste")
			(net "PVDDCR_CPU1_P0")
		)
		(pad "2" smd circle
			(at -0.40005 0 180)
			(size 0 0)
			(layers "B.Cu" "B.Mask" "B.Paste")
			(net "GND")
		)
	)
	(footprint ""
		(layer "B.Cu")
		(at 331.793342 -393.04468 180)
		(property "Reference" "R1033"
			(at 0 0 0)
			(layer "B.SilkS")
			(hide yes)
			(effects
				(font
					(size 1.27 1.27)
				)
				(justify mirror)
			)
		)
		(property "Value" ""
			(at 0 0 0)
			(layer "B.Fab")
			(effects
				(font
					(size 1.27 1.27)
				)
				(justify mirror)
			)
		)
		(duplicate_pad_numbers_are_jumpers no)
		(fp_line
			(start 0.32512 0.175006)
			(end 0.32512 -0.175006)
			(stroke
				(width 0.1)
				(type default)
			)
			(layer "B.Fab")
		)
		(fp_line
			(start 0.32512 -0.175006)
			(end -0.32512 -0.175006)
			(stroke
				(width 0.1)
				(type default)
			)
			(layer "B.Fab")
		)
		(fp_line
			(start -0.32512 0.175006)
			(end 0.32512 0.175006)
			(stroke
				(width 0.1)
				(type default)
			)
			(layer "B.Fab")
		)
		(fp_line
			(start -0.32512 -0.175006)
			(end -0.32512 0.175006)
			(stroke
				(width 0.1)
				(type default)
			)
			(layer "B.Fab")
		)
		(pad "1" smd rect
			(at 0.2667 0)
			(size 0.3048 0.381)
			(layers "B.Cu" "B.Mask" "B.Paste")
			(net "TEST1_RT_CPU0_P1")
		)
		(pad "2" smd rect
			(at -0.2667 0 180)
			(size 0.3048 0.381)
			(layers "B.Cu" "B.Mask" "B.Paste")
			(net "GND")
		)
	)
	(footprint ""
		(layer "B.Cu")
		(at 124.741432 -261.93623)
		(property "Reference" "C2435"
			(at 0 0 0)
			(layer "B.SilkS")
			(hide yes)
			(effects
				(font
					(size 1.27 1.27)
				)
				(justify mirror)
			)
		)
		(property "Value" ""
			(at 0 0 0)
			(layer "B.Fab")
			(effects
				(font
					(size 1.27 1.27)
				)
				(justify mirror)
			)
		)
		(duplicate_pad_numbers_are_jumpers no)
		(fp_line
			(start -0.7874 -0.4064)
			(end -0.7874 0.4064)
			(stroke
				(width 0.1524)
				(type default)
			)
			(layer "B.SilkS")
		)
		(fp_line
			(start -0.7874 0.4064)
			(end 0.7874 0.4064)
			(stroke
				(width 0.1524)
				(type default)
			)
			(layer "B.SilkS")
		)
		(fp_line
			(start 0.7874 -0.4064)
			(end -0.7874 -0.4064)
			(stroke
				(width 0.1524)
				(type default)
			)
			(layer "B.SilkS")
		)
		(fp_line
			(start 0.7874 0.4064)
			(end 0.7874 -0.4064)
			(stroke
				(width 0.1524)
				(type default)
			)
			(layer "B.SilkS")
		)
		(fp_line
			(start -0.67945 -0.3048)
			(end -0.67945 0.3048)
			(stroke
				(width 0.1)
				(type default)
			)
			(layer "B.Fab")
		)
		(fp_line
			(start -0.67945 0.3048)
			(end -0.120396 0.3048)
			(stroke
				(width 0.1)
				(type default)
			)
			(layer "B.Fab")
		)
		(fp_line
			(start -0.12065 -0.3048)
			(end -0.67945 -0.3048)
			(stroke
				(width 0.1)
				(type default)
			)
			(layer "B.Fab")
		)
		(fp_line
			(start -0.12065 -0.2794)
			(end -0.12065 -0.3048)
			(stroke
				(width 0.1)
				(type default)
			)
			(layer "B.Fab")
		)
		(fp_line
			(start -0.120396 0.2794)
			(end 0.12065 0.2794)
			(stroke
				(width 0.1)
				(type default)
			)
			(layer "B.Fab")
		)
		(fp_line
			(start -0.120396 0.3048)
			(end -0.120396 0.2794)
			(stroke
				(width 0.1)
				(type default)
			)
			(layer "B.Fab")
		)
		(fp_line
			(start 0.12065 -0.305054)
			(end 0.12065 -0.2794)
			(stroke
				(width 0.1)
				(type default)
			)
			(layer "B.Fab")
		)
		(fp_line
			(start 0.12065 -0.2794)
			(end -0.12065 -0.2794)
			(stroke
				(width 0.1)
				(type default)
			)
			(layer "B.Fab")
		)
		(fp_line
			(start 0.12065 0.2794)
			(end 0.12065 0.3048)
			(stroke
				(width 0.1)
				(type default)
			)
			(layer "B.Fab")
		)
		(fp_line
			(start 0.12065 0.3048)
			(end 0.67945 0.3048)
			(stroke
				(width 0.1)
				(type default)
			)
			(layer "B.Fab")
		)
		(fp_line
			(start 0.67945 -0.305054)
			(end 0.12065 -0.305054)
			(stroke
				(width 0.1)
				(type default)
			)
			(layer "B.Fab")
		)
		(fp_line
			(start 0.67945 0.3048)
			(end 0.67945 -0.305054)
			(stroke
				(width 0.1)
				(type default)
			)
			(layer "B.Fab")
		)
		(pad "1" smd circle
			(at 0.40005 0 180)
			(size 0 0)
			(layers "B.Cu" "B.Mask" "B.Paste")
			(net "PVDDCR_SOC_P1")
		)
		(pad "2" smd circle
			(at -0.40005 0 180)
			(size 0 0)
			(layers "B.Cu" "B.Mask" "B.Paste")
			(net "GND")
		)
	)
	(footprint ""
		(layer "B.Cu")
		(at 117.018562 -388.011162 -90)
		(property "Reference" "C450"
			(at 0 0 90)
			(layer "B.SilkS")
			(hide yes)
			(effects
				(font
					(size 1.27 1.27)
				)
				(justify mirror)
			)
		)
		(property "Value" ""
			(at 0 0 90)
			(layer "B.Fab")
			(effects
				(font
					(size 1.27 1.27)
				)
				(justify mirror)
			)
		)
		(duplicate_pad_numbers_are_jumpers no)
		(fp_line
			(start -0.299974 0.150114)
			(end 0.299974 0.150114)
			(stroke
				(width 0.1)
				(type default)
			)
			(layer "B.Fab")
		)
		(fp_line
			(start 0.299974 0.150114)
			(end 0.299974 -0.150114)
			(stroke
				(width 0.1)
				(type default)
			)
			(layer "B.Fab")
		)
		(fp_line
			(start -0.299974 -0.150114)
			(end -0.299974 0.150114)
			(stroke
				(width 0.1)
				(type default)
			)
			(layer "B.Fab")
		)
		(fp_line
			(start 0.299974 -0.150114)
			(end -0.299974 -0.150114)
			(stroke
				(width 0.1)
				(type default)
			)
			(layer "B.Fab")
		)
		(pad "1" smd rect
			(at 0.2667 0 90)
			(size 0.3048 0.381)
			(layers "B.Cu" "B.Mask" "B.Paste")
			(net "P0V9_CPU1_RT3_2A")
		)
		(pad "2" smd rect
			(at -0.2667 0 90)
			(size 0.3048 0.381)
			(layers "B.Cu" "B.Mask" "B.Paste")
			(net "GND")
		)
	)
	(footprint ""
		(layer "B.Cu")
		(at 105.960164 -256.505456 180)
		(property "Reference" "C2660"
			(at 0 0 0)
			(layer "B.SilkS")
			(hide yes)
			(effects
				(font
					(size 1.27 1.27)
				)
				(justify mirror)
			)
		)
		(property "Value" ""
			(at 0 0 0)
			(layer "B.Fab")
			(effects
				(font
					(size 1.27 1.27)
				)
				(justify mirror)
			)
		)
		(duplicate_pad_numbers_are_jumpers no)
		(fp_line
			(start 0.7874 0.4064)
			(end 0.7874 -0.4064)
			(stroke
				(width 0.1524)
				(type default)
			)
			(layer "B.SilkS")
		)
		(fp_line
			(start 0.7874 -0.4064)
			(end -0.7874 -0.4064)
			(stroke
				(width 0.1524)
				(type default)
			)
			(layer "B.SilkS")
		)
		(fp_line
			(start -0.7874 0.4064)
			(end 0.7874 0.4064)
			(stroke
				(width 0.1524)
				(type default)
			)
			(layer "B.SilkS")
		)
		(fp_line
			(start -0.7874 -0.4064)
			(end -0.7874 0.4064)
			(stroke
				(width 0.1524)
				(type default)
			)
			(layer "B.SilkS")
		)
		(fp_line
			(start 0.67945 0.3048)
			(end 0.67945 -0.305054)
			(stroke
				(width 0.1)
				(type default)
			)
			(layer "B.Fab")
		)
		(fp_line
			(start 0.67945 -0.305054)
			(end 0.12065 -0.305054)
			(stroke
				(width 0.1)
				(type default)
			)
			(layer "B.Fab")
		)
		(fp_line
			(start 0.12065 0.3048)
			(end 0.67945 0.3048)
			(stroke
				(width 0.1)
				(type default)
			)
			(layer "B.Fab")
		)
		(fp_line
			(start 0.12065 0.2794)
			(end 0.12065 0.3048)
			(stroke
				(width 0.1)
				(type default)
			)
			(layer "B.Fab")
		)
		(fp_line
			(start 0.12065 -0.2794)
			(end -0.12065 -0.2794)
			(stroke
				(width 0.1)
				(type default)
			)
			(layer "B.Fab")
		)
		(fp_line
			(start 0.12065 -0.305054)
			(end 0.12065 -0.2794)
			(stroke
				(width 0.1)
				(type default)
			)
			(layer "B.Fab")
		)
		(fp_line
			(start -0.120396 0.3048)
			(end -0.120396 0.2794)
			(stroke
				(width 0.1)
				(type default)
			)
			(layer "B.Fab")
		)
		(fp_line
			(start -0.120396 0.2794)
			(end 0.12065 0.2794)
			(stroke
				(width 0.1)
				(type default)
			)
			(layer "B.Fab")
		)
		(fp_line
			(start -0.12065 -0.2794)
			(end -0.12065 -0.3048)
			(stroke
				(width 0.1)
				(type default)
			)
			(layer "B.Fab")
		)
		(fp_line
			(start -0.12065 -0.3048)
			(end -0.67945 -0.3048)
			(stroke
				(width 0.1)
				(type default)
			)
			(layer "B.Fab")
		)
		(fp_line
			(start -0.67945 0.3048)
			(end -0.120396 0.3048)
			(stroke
				(width 0.1)
				(type default)
			)
			(layer "B.Fab")
		)
		(fp_line
			(start -0.67945 -0.3048)
			(end -0.67945 0.3048)
			(stroke
				(width 0.1)
				(type default)
			)
			(layer "B.Fab")
		)
		(pad "1" smd circle
			(at 0.40005 0)
			(size 0 0)
			(layers "B.Cu" "B.Mask" "B.Paste")
			(net "PVDD18_S5_P1")
		)
		(pad "2" smd circle
			(at -0.40005 0)
			(size 0 0)
			(layers "B.Cu" "B.Mask" "B.Paste")
			(net "GND")
		)
	)
	(footprint ""
		(layer "B.Cu")
		(at 146.3548 -13.772388 90)
		(property "Reference" "R4087"
			(at 0 0 90)
			(layer "B.SilkS")
			(hide yes)
			(effects
				(font
					(size 1.27 1.27)
				)
				(justify mirror)
			)
		)
		(property "Value" ""
			(at 0 0 90)
			(layer "B.Fab")
			(effects
				(font
					(size 1.27 1.27)
				)
				(justify mirror)
			)
		)
		(duplicate_pad_numbers_are_jumpers no)
		(fp_line
			(start 0.7874 -0.4064)
			(end -0.7874 -0.4064)
			(stroke
				(width 0.1524)
				(type default)
			)
			(layer "B.SilkS")
		)
		(fp_line
			(start -0.7874 -0.4064)
			(end -0.7874 0.4064)
			(stroke
				(width 0.1524)
				(type default)
			)
			(layer "B.SilkS")
		)
		(fp_line
			(start 0.7874 0.4064)
			(end 0.7874 -0.4064)
			(stroke
				(width 0.1524)
				(type default)
			)
			(layer "B.SilkS")
		)
		(fp_line
			(start -0.7874 0.4064)
			(end 0.7874 0.4064)
			(stroke
				(width 0.1524)
				(type default)
			)
			(layer "B.SilkS")
		)
		(fp_line
			(start 0.67945 -0.305054)
			(end 0.12065 -0.305054)
			(stroke
				(width 0.1)
				(type default)
			)
			(layer "B.Fab")
		)
		(fp_line
			(start 0.12065 -0.305054)
			(end 0.12065 -0.2794)
			(stroke
				(width 0.1)
				(type default)
			)
			(layer "B.Fab")
		)
		(fp_line
			(start -0.12065 -0.3048)
			(end -0.67945 -0.3048)
			(stroke
				(width 0.1)
				(type default)
			)
			(layer "B.Fab")
		)
		(fp_line
			(start -0.67945 -0.3048)
			(end -0.67945 0.3048)
			(stroke
				(width 0.1)
				(type default)
			)
			(layer "B.Fab")
		)
		(fp_line
			(start 0.12065 -0.2794)
			(end -0.12065 -0.2794)
			(stroke
				(width 0.1)
				(type default)
			)
			(layer "B.Fab")
		)
		(fp_line
			(start -0.12065 -0.2794)
			(end -0.12065 -0.3048)
			(stroke
				(width 0.1)
				(type default)
			)
			(layer "B.Fab")
		)
		(fp_line
			(start 0.12065 0.2794)
			(end 0.12065 0.3048)
			(stroke
				(width 0.1)
				(type default)
			)
			(layer "B.Fab")
		)
		(fp_line
			(start -0.120396 0.2794)
			(end 0.12065 0.2794)
			(stroke
				(width 0.1)
				(type default)
			)
			(layer "B.Fab")
		)
		(fp_line
			(start 0.67945 0.3048)
			(end 0.67945 -0.305054)
			(stroke
				(width 0.1)
				(type default)
			)
			(layer "B.Fab")
		)
		(fp_line
			(start 0.12065 0.3048)
			(end 0.67945 0.3048)
			(stroke
				(width 0.1)
				(type default)
			)
			(layer "B.Fab")
		)
		(fp_line
			(start -0.120396 0.3048)
			(end -0.120396 0.2794)
			(stroke
				(width 0.1)
				(type default)
			)
			(layer "B.Fab")
		)
		(fp_line
			(start -0.67945 0.3048)
			(end -0.120396 0.3048)
			(stroke
				(width 0.1)
				(type default)
			)
			(layer "B.Fab")
		)
		(pad "1" smd circle
			(at 0.40005 0 270)
			(size 0 0)
			(layers "B.Cu" "B.Mask" "B.Paste")
			(net "FW_RECOVERY_R")
		)
		(pad "2" smd circle
			(at -0.40005 0 270)
			(size 0 0)
			(layers "B.Cu" "B.Mask" "B.Paste")
			(net "FW_RECOVERY")
		)
	)
)
